(kicad_pcb
	(version 20241229)
	(generator "pcbnew")
	(generator_version "9.0")
	(general
		(thickness 1.6642)
		(legacy_teardrops no)
	)
	(paper "A3")
	(title_block
		(title "PolarFire SoM")
		(date "2025-07-22")
		(rev "1.1.4")
		(company "Antmicro Ltd")
		(comment 1 "www.antmicro.com")
		(comment 9 "footprints 99-103 of 470")
	)
	(layers
		(0 "F.Cu" mixed)
		(4 "In1.Cu" power)
		(6 "In2.Cu" signal)
		(8 "In3.Cu" power)
		(10 "In4.Cu" signal)
		(12 "In5.Cu" power)
		(14 "In6.Cu" power)
		(16 "In7.Cu" signal)
		(18 "In8.Cu" power)
		(20 "In9.Cu" signal)
		(22 "In10.Cu" power)
		(24 "In11.Cu" signal)
		(26 "In12.Cu" signal)
		(2 "B.Cu" mixed)
		(9 "F.Adhes" user "F.Adhesive")
		(11 "B.Adhes" user "B.Adhesive")
		(13 "F.Paste" user)
		(15 "B.Paste" user)
		(5 "F.SilkS" user "F.Silkscreen")
		(7 "B.SilkS" user "B.Silkscreen")
		(1 "F.Mask" user)
		(3 "B.Mask" user)
		(17 "Dwgs.User" user "User.Drawings")
		(19 "Cmts.User" user "User.Comments")
		(21 "Eco1.User" user "User.Eco1")
		(23 "Eco2.User" user "User.Eco2")
		(25 "Edge.Cuts" user)
		(27 "Margin" user)
		(31 "F.CrtYd" user "F.Courtyard")
		(29 "B.CrtYd" user "B.Courtyard")
		(35 "F.Fab" user)
		(33 "B.Fab" user)
	)
	(footprint "antmicro-footprints:R_0402_1005Metric"
		(layer "F.Cu")
		(at 204.35 120.75 90)
		(descr "Resistor SMD 0402")
		(tags "resistor SMD 0402")
		(property "Reference" "R57"
			(at -1.85 4 90)
			(layer "F.SilkS")
			(effects
				(font
					(size 0.7 0.7)
					(thickness 0.15)
				)
				(justify left bottom)
			)
		)
		(property "Value" "R_0R_0402"
			(at -1.011843 1.772047 90)
			(layer "F.Fab")
			(hide yes)
			(effects
				(font
					(size 0.7 0.7)
					(thickness 0.15)
				)
				(justify left bottom)
			)
		)
		(property "Datasheet" "https://industrial.panasonic.com/cdbs/www-data/pdf/RDA0000/AOA0000C301.pdf"
			(at 0 0 90)
			(layer "F.Fab")
			(hide yes)
			(effects
				(font
					(size 1.27 1.27)
					(thickness 0.15)
				)
			)
		)
		(property "Description" "SMD Chip Resistor, Jumper, 0 ohm, 100 mW, 0402 [1005 Metric], Thick Film, General Purpose"
			(at 0 0 90)
			(layer "F.Fab")
			(hide yes)
			(effects
				(font
					(size 1.27 1.27)
					(thickness 0.15)
				)
			)
		)
		(property "Author" "Antmicro"
			(at 325.1 -83.6 0)
			(layer "F.Fab")
			(hide yes)
			(effects
				(font
					(size 1 1)
					(thickness 0.15)
				)
			)
		)
		(property "Current" "1A"
			(at 325.1 -83.6 0)
			(layer "F.Fab")
			(hide yes)
			(effects
				(font
					(size 1 1)
					(thickness 0.15)
				)
			)
		)
		(property "License" "Apache-2.0"
			(at 325.1 -83.6 0)
			(layer "F.Fab")
			(hide yes)
			(effects
				(font
					(size 1 1)
					(thickness 0.15)
				)
			)
		)
		(property "MPN" "ERJ2GE0R00X"
			(at 325.1 -83.6 0)
			(layer "F.Fab")
			(hide yes)
			(effects
				(font
					(size 1 1)
					(thickness 0.15)
				)
			)
		)
		(property "Manufacturer" "Panasonic"
			(at 325.1 -83.6 0)
			(layer "F.Fab")
			(hide yes)
			(effects
				(font
					(size 1 1)
					(thickness 0.15)
				)
			)
		)
		(property "Public" ""
			(at 325.1 -83.6 0)
			(layer "F.Fab")
			(hide yes)
			(effects
				(font
					(size 1 1)
					(thickness 0.15)
				)
			)
		)
		(property "Tolerance" "~"
			(at 325.1 -83.6 0)
			(layer "F.Fab")
			(hide yes)
			(effects
				(font
					(size 1 1)
					(thickness 0.15)
				)
			)
		)
		(property "Val" "0R"
			(at 325.1 -83.6 0)
			(layer "F.Fab")
			(hide yes)
			(effects
				(font
					(size 1 1)
					(thickness 0.15)
				)
			)
		)
		(sheetname "/FPGA MSSIO/")
		(sheetfile "fpga-mssio.kicad_sch")
		(attr smd)
		(fp_rect
			(start -0.925 -0.47)
			(end 0.925 0.47)
			(stroke
				(width 0.05)
				(type default)
			)
			(fill no)
			(layer "F.CrtYd")
		)
		(fp_rect
			(start -0.5 -0.25)
			(end 0.5 0.25)
			(stroke
				(width 0.15)
				(type solid)
			)
			(fill no)
			(layer "F.Fab")
		)
		(fp_text user "Author: Antmicro"
			(at -0.95 4.169 90)
			(layer "F.Fab")
			(effects
				(font
					(size 0.7 0.7)
					(thickness 0.15)
				)
				(justify left bottom)
			)
		)
		(fp_text user "${REFERENCE}"
			(at -0.95 3.168 90)
			(layer "F.Fab")
			(effects
				(font
					(size 0.7 0.7)
					(thickness 0.15)
				)
				(justify left bottom)
			)
		)
		(fp_text user "License: Apache-2.0"
			(at -0.95 5.169 90)
			(layer "F.Fab")
			(effects
				(font
					(size 0.7 0.7)
					(thickness 0.15)
				)
				(justify left bottom)
			)
		)
		(pad "1" smd roundrect
			(at -0.48 0 90)
			(size 0.59 0.64)
			(layers "F.Cu" "F.Mask" "F.Paste")
			(roundrect_rratio 0.25)
			(net 100 "/FPGA MSSIO/SUPPLY.SDA")
			(pintype "passive")
		)
		(pad "2" smd roundrect
			(at 0.48 0 90)
			(size 0.59 0.64)
			(layers "F.Cu" "F.Mask" "F.Paste")
			(roundrect_rratio 0.25)
			(net 101 "/FPGA MSSIO/ID.SDA")
			(pintype "passive")
		)
	)
	(footprint "antmicro-footprints:TP_SMD_0.75mm"
		(layer "F.Cu")
		(at 227.2 148.45)
		(property "Reference" "TP8"
			(at 10.51 3.29 0)
			(layer "F.SilkS")
			(hide yes)
			(effects
				(font
					(size 0.7 0.7)
					(thickness 0.15)
				)
				(justify left bottom)
			)
		)
		(property "Value" "TP_0.75mm_SMD"
			(at 0 1.2 0)
			(layer "F.Fab")
			(hide yes)
			(effects
				(font
					(size 0.7 0.7)
					(thickness 0.15)
				)
				(justify left bottom)
			)
		)
		(property "Description" "SMT test point"
			(at 0 0 0)
			(layer "F.Fab")
			(hide yes)
			(effects
				(font
					(size 1.27 1.27)
					(thickness 0.15)
				)
			)
		)
		(property "Author" "Antmicro"
			(at 0 0 0)
			(layer "F.Fab")
			(hide yes)
			(effects
				(font
					(size 1 1)
					(thickness 0.15)
				)
			)
		)
		(property "License" "Apache-2.0"
			(at 0 0 0)
			(layer "F.Fab")
			(hide yes)
			(effects
				(font
					(size 1 1)
					(thickness 0.15)
				)
			)
		)
		(property "MPN" ""
			(at 0 0 0)
			(layer "F.Fab")
			(hide yes)
			(effects
				(font
					(size 1 1)
					(thickness 0.15)
				)
			)
		)
		(property "Manufacturer" ""
			(at 0 0 0)
			(layer "F.Fab")
			(hide yes)
			(effects
				(font
					(size 1 1)
					(thickness 0.15)
				)
			)
		)
		(property "Public" "False"
			(at 0 0 0)
			(layer "F.Fab")
			(hide yes)
			(effects
				(font
					(size 1 1)
					(thickness 0.15)
				)
			)
		)
		(sheetname "/WiFi_Bluetooth/")
		(sheetfile "wifi_bt.kicad_sch")
		(attr exclude_from_pos_files exclude_from_bom)
		(fp_circle
			(center 0 0)
			(end 0.475 0)
			(stroke
				(width 0.05)
				(type default)
			)
			(fill no)
			(layer "F.CrtYd")
		)
		(fp_text user "${REFERENCE}"
			(at -0.4 2.7 0)
			(layer "F.Fab")
			(effects
				(font
					(size 0.7 0.7)
					(thickness 0.15)
				)
				(justify left bottom)
			)
		)
		(fp_text user "License: Apache-2.0"
			(at -0.4 5.101 0)
			(layer "F.Fab")
			(effects
				(font
					(size 0.7 0.7)
					(thickness 0.15)
				)
				(justify left bottom)
			)
		)
		(fp_text user "Author: Antmicro"
			(at -0.4 3.901 0)
			(layer "F.Fab")
			(effects
				(font
					(size 0.7 0.7)
					(thickness 0.15)
				)
				(justify left bottom)
			)
		)
		(pad "1" smd circle
			(at 0 0)
			(size 0.75 0.75)
			(layers "F.Cu" "F.Mask")
			(net 297 "Net-(U26A-BT_UART_CTS_N)")
			(pinfunction "1")
			(pintype "passive")
		)
	)
	(footprint "antmicro-footprints:L_0806_2016Metric"
		(layer "F.Cu")
		(at 183.375 139.903695 90)
		(property "Reference" "L3"
			(at 1.683695 -0.665 180)
			(layer "F.SilkS")
			(effects
				(font
					(size 0.7 0.7)
					(thickness 0.15)
				)
				(justify left bottom)
			)
		)
		(property "Value" "L_1u5_2.8A_0806"
			(at 0 2 90)
			(layer "F.Fab")
			(hide yes)
			(effects
				(font
					(size 0.7 0.7)
					(thickness 0.15)
				)
				(justify left bottom)
			)
		)
		(property "Datasheet" "https://abracon.com/datasheets/AOTA-B201610S.pdf"
			(at 0 0 90)
			(layer "F.Fab")
			(hide yes)
			(effects
				(font
					(size 1.27 1.27)
					(thickness 0.15)
				)
			)
		)
		(property "Description" "Power Inductor (SMT), 1.5 µH, 0.074 ohm, 2.8 A, AOTA-B201610S"
			(at 0 0 90)
			(layer "F.Fab")
			(hide yes)
			(effects
				(font
					(size 1.27 1.27)
					(thickness 0.15)
				)
			)
		)
		(property "Author" "Antmicro"
			(at 323.278695 -43.471305 0)
			(layer "F.Fab")
			(hide yes)
			(effects
				(font
					(size 1 1)
					(thickness 0.15)
				)
			)
		)
		(property "IMax" "2.8 A"
			(at 323.278695 -43.471305 0)
			(layer "F.Fab")
			(hide yes)
			(effects
				(font
					(size 1 1)
					(thickness 0.15)
				)
			)
		)
		(property "ISat" "3.5 A"
			(at 323.278695 -43.471305 0)
			(layer "F.Fab")
			(hide yes)
			(effects
				(font
					(size 1 1)
					(thickness 0.15)
				)
			)
		)
		(property "License" "Apache-2.0"
			(at 323.278695 -43.471305 0)
			(layer "F.Fab")
			(hide yes)
			(effects
				(font
					(size 1 1)
					(thickness 0.15)
				)
			)
		)
		(property "MPN" "AOTA-B201610S1R5MT"
			(at 323.278695 -43.471305 0)
			(layer "F.Fab")
			(hide yes)
			(effects
				(font
					(size 1 1)
					(thickness 0.15)
				)
			)
		)
		(property "Manufacturer" "Abracon"
			(at 323.278695 -43.471305 0)
			(layer "F.Fab")
			(hide yes)
			(effects
				(font
					(size 1 1)
					(thickness 0.15)
				)
			)
		)
		(property "Public" ""
			(at 323.278695 -43.471305 0)
			(layer "F.Fab")
			(hide yes)
			(effects
				(font
					(size 1 1)
					(thickness 0.15)
				)
			)
		)
		(property "Size" "2.0x1.6"
			(at 323.278695 -43.471305 0)
			(layer "F.Fab")
			(hide yes)
			(effects
				(font
					(size 1 1)
					(thickness 0.15)
				)
			)
		)
		(property "Val" "1.5u/2.8A"
			(at 323.278695 -43.471305 0)
			(layer "F.Fab")
			(hide yes)
			(effects
				(font
					(size 1 1)
					(thickness 0.15)
				)
			)
		)
		(sheetname "/Supply/")
		(sheetfile "supply.kicad_sch")
		(attr smd)
		(fp_line
			(start -0.3 -0.9)
			(end 0.298 -0.9)
			(stroke
				(width 0.15)
				(type solid)
			)
			(layer "F.SilkS")
		)
		(fp_line
			(start -0.301 0.9)
			(end 0.299 0.9)
			(stroke
				(width 0.15)
				(type solid)
			)
			(layer "F.SilkS")
		)
		(fp_rect
			(start -1.75 -1.05)
			(end 1.75 1.05)
			(stroke
				(width 0.05)
				(type solid)
			)
			(fill no)
			(layer "F.CrtYd")
		)
		(fp_rect
			(start -0.951 -0.882)
			(end 0.949 0.875)
			(stroke
				(width 0.15)
				(type solid)
			)
			(fill no)
			(layer "F.Fab")
		)
		(fp_text user "${REFERENCE}"
			(at -1.9 3.1 90)
			(layer "F.Fab")
			(effects
				(font
					(size 0.7 0.7)
					(thickness 0.15)
				)
				(justify left bottom)
			)
		)
		(fp_text user "Author: Antmicro"
			(at -1.9 4.4 90)
			(layer "F.Fab")
			(effects
				(font
					(size 0.7 0.7)
					(thickness 0.15)
				)
				(justify left bottom)
			)
		)
		(fp_text user "License: Apache-2.0"
			(at -1.9 5.75 90)
			(layer "F.Fab")
			(effects
				(font
					(size 0.7 0.7)
					(thickness 0.15)
				)
				(justify left bottom)
			)
		)
		(pad "1" smd roundrect
			(at -1.1 -0.001 90)
			(size 1 1.8)
			(layers "F.Cu" "F.Mask" "F.Paste")
			(roundrect_rratio 0.15)
			(net 175 "Net-(U7-SW2)")
			(pintype "passive")
		)
		(pad "2" smd roundrect
			(at 1.1 -0.001 90)
			(size 1 1.8)
			(layers "F.Cu" "F.Mask" "F.Paste")
			(roundrect_rratio 0.15)
			(net 272 "/Supply/SENSE3_P")
			(pintype "passive")
		)
	)
	(footprint "antmicro-footprints:C_0402_1005Metric"
		(layer "F.Cu")
		(at 194.85 120.95 -90)
		(descr "Capacitor SMD 0402")
		(tags "capacitor SMD 0402")
		(property "Reference" "C131"
			(at -1.18 -4.37 90)
			(layer "F.SilkS")
			(effects
				(font
					(size 0.7 0.7)
					(thickness 0.15)
				)
				(justify right bottom)
			)
		)
		(property "Value" "C_100n_0402"
			(at -1.022927 2.155213 90)
			(layer "F.Fab")
			(hide yes)
			(effects
				(font
					(size 0.7 0.7)
					(thickness 0.15)
				)
				(justify right bottom)
			)
		)
		(property "Datasheet" "https://www.murata.com/products/productdetail?partno=GRM155R61H104KE14%23"
			(at 0 0 270)
			(layer "F.Fab")
			(hide yes)
			(effects
				(font
					(size 1.27 1.27)
					(thickness 0.15)
				)
			)
		)
		(property "Description" "SMD Multilayer Ceramic Capacitor, 0.1 µF, 50 V, 0402 [1005 Metric], ± 10%, X5R, GRM Series"
			(at 0 0 270)
			(layer "F.Fab")
			(hide yes)
			(effects
				(font
					(size 1.27 1.27)
					(thickness 0.15)
				)
			)
		)
		(property "Author" "Antmicro"
			(at 73.9 315.8 0)
			(layer "F.Fab")
			(hide yes)
			(effects
				(font
					(size 1 1)
					(thickness 0.15)
				)
			)
		)
		(property "Dielectric" "X5R"
			(at 73.9 315.8 0)
			(layer "F.Fab")
			(hide yes)
			(effects
				(font
					(size 1 1)
					(thickness 0.15)
				)
			)
		)
		(property "License" "Apache-2.0"
			(at 73.9 315.8 0)
			(layer "F.Fab")
			(hide yes)
			(effects
				(font
					(size 1 1)
					(thickness 0.15)
				)
			)
		)
		(property "MPN" "GRM155R61H104KE14D"
			(at 73.9 315.8 0)
			(layer "F.Fab")
			(hide yes)
			(effects
				(font
					(size 1 1)
					(thickness 0.15)
				)
			)
		)
		(property "Manufacturer" "Murata"
			(at 73.9 315.8 0)
			(layer "F.Fab")
			(hide yes)
			(effects
				(font
					(size 1 1)
					(thickness 0.15)
				)
			)
		)
		(property "Public" ""
			(at 73.9 315.8 0)
			(layer "F.Fab")
			(hide yes)
			(effects
				(font
					(size 1 1)
					(thickness 0.15)
				)
			)
		)
		(property "Val" "100n"
			(at 73.9 315.8 0)
			(layer "F.Fab")
			(hide yes)
			(effects
				(font
					(size 1 1)
					(thickness 0.15)
				)
			)
		)
		(property "Voltage" "50V"
			(at 73.9 315.8 0)
			(layer "F.Fab")
			(hide yes)
			(effects
				(font
					(size 1 1)
					(thickness 0.15)
				)
			)
		)
		(sheetname "/FPGA GPIO/")
		(sheetfile "fpga-gpio.kicad_sch")
		(attr smd)
		(fp_rect
			(start -0.925 -0.47)
			(end 0.925 0.47)
			(stroke
				(width 0.05)
				(type default)
			)
			(fill no)
			(layer "F.CrtYd")
		)
		(fp_line
			(start -0.494 0.248)
			(end -0.494 -0.25)
			(stroke
				(width 0.15)
				(type solid)
			)
			(layer "F.Fab")
		)
		(fp_line
			(start 0.504 0.248)
			(end -0.494 0.248)
			(stroke
				(width 0.15)
				(type solid)
			)
			(layer "F.Fab")
		)
		(fp_line
			(start -0.494 -0.25)
			(end 0.504 -0.25)
			(stroke
				(width 0.15)
				(type solid)
			)
			(layer "F.Fab")
		)
		(fp_line
			(start 0.504 -0.25)
			(end 0.504 0.248)
			(stroke
				(width 0.15)
				(type solid)
			)
			(layer "F.Fab")
		)
		(fp_text user "License: Apache-2.0"
			(at -0.939 5.799 270)
			(layer "F.Fab")
			(effects
				(font
					(size 0.7 0.7)
					(thickness 0.15)
				)
				(justify left bottom)
			)
		)
		(fp_text user "${REFERENCE}"
			(at -0.939 4.599 270)
			(layer "F.Fab")
			(effects
				(font
					(size 0.7 0.7)
					(thickness 0.15)
				)
				(justify left bottom)
			)
		)
		(fp_text user "Author: Antmicro"
			(at -0.939 3.399 270)
			(layer "F.Fab")
			(effects
				(font
					(size 0.7 0.7)
					(thickness 0.15)
				)
				(justify left bottom)
			)
		)
		(pad "1" smd roundrect
			(at -0.48 0 270)
			(size 0.59 0.64)
			(layers "F.Cu" "F.Mask" "F.Paste")
			(roundrect_rratio 0.25)
			(net 50 "+3V3")
			(pintype "passive")
		)
		(pad "2" smd roundrect
			(at 0.48 0 270)
			(size 0.59 0.64)
			(layers "F.Cu" "F.Mask" "F.Paste")
			(roundrect_rratio 0.25)
			(net 417 "GND")
			(pintype "passive")
		)
	)
	(footprint "antmicro-footprints:D_0402_1005Metric"
		(layer "F.Cu")
		(at 210.198712 151.829798 -90)
		(property "Reference" "D3"
			(at -1.169798 -1.381288 90)
			(layer "F.SilkS")
			(effects
				(font
					(size 0.7 0.7)
					(thickness 0.15)
				)
				(justify right bottom)
			)
		)
		(property "Value" "AXGD10402KR"
			(at -2.54 2.54 90)
			(layer "F.Fab")
			(hide yes)
			(effects
				(font
					(size 0.7 0.7)
					(thickness 0.15)
				)
				(justify right bottom)
			)
		)
		(property "Datasheet" "https://www.littelfuse.com/media?resourcetype=datasheets&itemid=020b2bf2-064c-4ff1-a898-b4ec805b2fea&filename=littelfuse-xtremeguard-axgd-datasheet"
			(at 0 0 270)
			(layer "F.Fab")
			(hide yes)
			(effects
				(font
					(size 1.27 1.27)
					(thickness 0.15)
				)
			)
		)
		(property "Description" "Bidirectional TVS, 30 kV,  0402, 24 V, 0.04 pF"
			(at 0 0 270)
			(layer "F.Fab")
			(hide yes)
			(effects
				(font
					(size 1.27 1.27)
					(thickness 0.15)
				)
			)
		)
		(property "Author" "Antmicro"
			(at 58.368914 362.02851 0)
			(layer "F.Fab")
			(hide yes)
			(effects
				(font
					(size 1 1)
					(thickness 0.15)
				)
			)
		)
		(property "License" "Apache-2.0"
			(at 58.368914 362.02851 0)
			(layer "F.Fab")
			(hide yes)
			(effects
				(font
					(size 1 1)
					(thickness 0.15)
				)
			)
		)
		(property "MPN" "AXGD10402KR"
			(at 58.368914 362.02851 0)
			(layer "F.Fab")
			(hide yes)
			(effects
				(font
					(size 1 1)
					(thickness 0.15)
				)
			)
		)
		(property "Manufacturer" "Littelfuse"
			(at 58.368914 362.02851 0)
			(layer "F.Fab")
			(hide yes)
			(effects
				(font
					(size 1 1)
					(thickness 0.15)
				)
			)
		)
		(property "Public" ""
			(at 58.368914 362.02851 0)
			(layer "F.Fab")
			(hide yes)
			(effects
				(font
					(size 1 1)
					(thickness 0.15)
				)
			)
		)
		(sheetname "/USB/")
		(sheetfile "usb.kicad_sch")
		(attr smd)
		(fp_line
			(start -0.1 0.255)
			(end 0.1 0.255)
			(stroke
				(width 0.15)
				(type solid)
			)
			(layer "F.SilkS")
		)
		(fp_line
			(start -0.875 -0.25)
			(end -0.875 0.25)
			(stroke
				(width 0.15)
				(type solid)
			)
			(layer "F.SilkS")
		)
		(fp_line
			(start 0.1 -0.255)
			(end -0.1 -0.255)
			(stroke
				(width 0.15)
				(type solid)
			)
			(layer "F.SilkS")
		)
		(fp_rect
			(start -0.925 -0.47)
			(end 0.925 0.47)
			(stroke
				(width 0.05)
				(type default)
			)
			(fill no)
			(layer "F.CrtYd")
		)
		(fp_line
			(start -0.51 0.255)
			(end -0.51 -0.255)
			(stroke
				(width 0.15)
				(type solid)
			)
			(layer "F.Fab")
		)
		(fp_line
			(start 0.51 0.255)
			(end -0.51 0.255)
			(stroke
				(width 0.15)
				(type solid)
			)
			(layer "F.Fab")
		)
		(fp_line
			(start -0.2 -0.25)
			(end -0.5 0.05)
			(stroke
				(width 0.15)
				(type solid)
			)
			(layer "F.Fab")
		)
		(fp_line
			(start -0.51 -0.255)
			(end 0.51 -0.255)
			(stroke
				(width 0.15)
				(type solid)
			)
			(layer "F.Fab")
		)
		(fp_line
			(start 0.51 -0.255)
			(end 0.51 0.255)
			(stroke
				(width 0.15)
				(type solid)
			)
			(layer "F.Fab")
		)
		(fp_text user "${REFERENCE}"
			(at -2.54 4.54 270)
			(layer "F.Fab")
			(effects
				(font
					(size 0.7 0.7)
					(thickness 0.15)
				)
				(justify left bottom)
			)
		)
		(fp_text user "Author: Antmicro"
			(at -2.54 6.94 270)
			(layer "F.Fab")
			(effects
				(font
					(size 0.7 0.7)
					(thickness 0.15)
				)
				(justify left bottom)
			)
		)
		(fp_text user "License: Apache-2.0"
			(at -2.54 5.74 270)
			(layer "F.Fab")
			(effects
				(font
					(size 0.7 0.7)
					(thickness 0.15)
				)
				(justify left bottom)
			)
		)
		(pad "1" smd roundrect
			(at -0.48 0 270)
			(size 0.59 0.64)
			(layers "F.Cu" "F.Mask" "F.Paste")
			(roundrect_rratio 0.25)
			(net 417 "GND")
			(pinfunction "C")
			(pintype "passive")
		)
		(pad "2" smd roundrect
			(at 0.48 0 270)
			(size 0.59 0.64)
			(layers "F.Cu" "F.Mask" "F.Paste")
			(roundrect_rratio 0.25)
			(net 16 "/Bottom Connector/CONN.D_P")
			(pinfunction "A")
			(pintype "passive")
		)
	)
)
